(kicad_pcb
	(version 20241229)
	(generator "pcbnew")
	(generator_version "9.0")
	(general
		(thickness 1.599998)
		(legacy_teardrops no)
	)
	(paper "A4")
	(title_block
		(title "Artix - Datacenter Secure Control Module (DC-SCM)")
		(date "2024-11-06")
		(rev "1.1.3")
		(comment 9 "footprint 266 of 544 (U7), pads 1-76 of 96")
	)
	(layers
		(0 "F.Cu" signal)
		(4 "In1.Cu" signal)
		(6 "In2.Cu" signal)
		(8 "In3.Cu" signal)
		(10 "In4.Cu" signal)
		(12 "In5.Cu" signal)
		(14 "In6.Cu" signal)
		(2 "B.Cu" signal)
		(9 "F.Adhes" user "F.Adhesive")
		(11 "B.Adhes" user "B.Adhesive")
		(13 "F.Paste" user)
		(15 "B.Paste" user)
		(5 "F.SilkS" user "F.Silkscreen")
		(7 "B.SilkS" user "B.Silkscreen")
		(1 "F.Mask" user)
		(3 "B.Mask" user)
		(17 "Dwgs.User" user "User.Drawings")
		(19 "Cmts.User" user "User.Comments")
		(21 "Eco1.User" user "User.Eco1")
		(23 "Eco2.User" user "User.Eco2")
		(25 "Edge.Cuts" user)
		(27 "Margin" user)
		(31 "F.CrtYd" user "F.Courtyard")
		(29 "B.CrtYd" user "B.Courtyard")
		(35 "F.Fab" user)
		(33 "B.Fab" user)
	)
	(footprint "antmicro-footprints:BGA-96-48_7.5x13.5mm_Layout9x16_P0.8mm"
		(layer "F.Cu")
		(at 98.175 147.175 90)
		(descr "Based on: https://www.alliancememory.com/wp-content/uploads/AllianceMemory_4G_DDR3L_AS4C256M16D3LC_March2020_Rev1.0.pdf")
		(property "Reference" "U7"
			(at -4 -7.3 90)
			(layer "F.SilkS")
			(effects
				(font
					(size 0.7 0.7)
					(thickness 0.15)
				)
				(justify left bottom)
			)
		)
		(property "Value" "AS4C256M16D3"
			(at -4 7.85 90)
			(layer "F.Fab")
			(effects
				(font
					(size 0.7 0.7)
					(thickness 0.15)
				)
				(justify left bottom)
			)
		)
		(property "Datasheet" "https://www.alliancememory.com/wp-content/uploads/AllianceMemory_4G_DDR3L_AS4C256M16D3LC_March2020_Rev1.0.pdf"
			(at 0 0 90)
			(layer "F.Fab")
			(effects
				(font
					(size 0.7 0.7)
					(thickness 0.15)
				)
				(justify left bottom)
			)
		)
		(property "Description" "SDRAM - DDR3 Memory IC 4Gbit Parallel 800 MHz 20 ns 96-FBGA (9x13)"
			(at 0 0 90)
			(layer "F.Fab")
			(effects
				(font
					(size 0.7 0.7)
					(thickness 0.15)
				)
				(justify left bottom)
			)
		)
		(property "Manufacturer" "Alliance Memory"
			(at 0 0 90)
			(unlocked yes)
			(layer "F.Fab")
			(hide yes)
			(effects
				(font
					(size 1 1)
					(thickness 0.15)
				)
			)
		)
		(property "MPN" "AS4C256M16D3LC-12BCN"
			(at 0 0 90)
			(unlocked yes)
			(layer "F.Fab")
			(hide yes)
			(effects
				(font
					(size 1 1)
					(thickness 0.15)
				)
			)
		)
		(property "Author" "Antmicro"
			(at 0 0 90)
			(unlocked yes)
			(layer "F.Fab")
			(hide yes)
			(effects
				(font
					(size 1 1)
					(thickness 0.15)
				)
			)
		)
		(property "License" "Apache-2.0"
			(at 0 0 90)
			(unlocked yes)
			(layer "F.Fab")
			(hide yes)
			(effects
				(font
					(size 1 1)
					(thickness 0.15)
				)
			)
		)
		(sheetname "/DDR3/")
		(sheetfile "ddr3.kicad_sch")
		(attr smd)
		(pad "A1" smd circle
			(at -3.2 -6 180)
			(size 0.41 0.41)
			(layers "F.Cu" "F.Mask" "F.Paste")
			(net 3 "VCC1V35")
			(pinfunction "VDDQ")
			(pintype "power_in")
			(solder_mask_margin 0.03)
		)
		(pad "A2" smd circle
			(at -2.4 -6 180)
			(size 0.41 0.41)
			(layers "F.Cu" "F.Mask" "F.Paste")
			(net 178 "DDR3_DQ13")
			(pinfunction "DQ13")
			(pintype "bidirectional")
			(solder_mask_margin 0.03)
		)
		(pad "A3" smd circle
			(at -1.6 -6 180)
			(size 0.41 0.41)
			(layers "F.Cu" "F.Mask" "F.Paste")
			(net 177 "DDR3_DQ15")
			(pinfunction "DQ15")
			(pintype "bidirectional")
			(solder_mask_margin 0.03)
		)
		(pad "A7" smd circle
			(at 1.6 -6 180)
			(size 0.41 0.41)
			(layers "F.Cu" "F.Mask" "F.Paste")
			(net 182 "DDR3_DQ12")
			(pinfunction "DQ12")
			(pintype "bidirectional")
			(solder_mask_margin 0.03)
		)
		(pad "A8" smd circle
			(at 2.4 -6 180)
			(size 0.41 0.41)
			(layers "F.Cu" "F.Mask" "F.Paste")
			(net 3 "VCC1V35")
			(pinfunction "VDDQ")
			(pintype "passive")
			(solder_mask_margin 0.03)
		)
		(pad "A9" smd circle
			(at 3.2 -6 180)
			(size 0.41 0.41)
			(layers "F.Cu" "F.Mask" "F.Paste")
			(net 1 "GND")
			(pinfunction "VSS")
			(pintype "power_in")
			(solder_mask_margin 0.03)
		)
		(pad "B1" smd circle
			(at -3.2 -5.2 180)
			(size 0.41 0.41)
			(layers "F.Cu" "F.Mask" "F.Paste")
			(net 1 "GND")
			(pinfunction "VSSQ")
			(pintype "power_in")
			(solder_mask_margin 0.03)
		)
		(pad "B2" smd circle
			(at -2.4 -5.2 180)
			(size 0.41 0.41)
			(layers "F.Cu" "F.Mask" "F.Paste")
			(net 3 "VCC1V35")
			(pinfunction "VDD")
			(pintype "power_in")
			(solder_mask_margin 0.03)
		)
		(pad "B3" smd circle
			(at -1.6 -5.2 180)
			(size 0.41 0.41)
			(layers "F.Cu" "F.Mask" "F.Paste")
			(net 1 "GND")
			(pinfunction "VSS")
			(pintype "passive")
			(solder_mask_margin 0.03)
		)
		(pad "B7" smd circle
			(at 1.6 -5.2 180)
			(size 0.41 0.41)
			(layers "F.Cu" "F.Mask" "F.Paste")
			(net 474 "DDR3_DQS1_N")
			(pinfunction "~{UDQS}")
			(pintype "bidirectional")
			(solder_mask_margin 0.03)
		)
		(pad "B8" smd circle
			(at 2.4 -5.2 180)
			(size 0.41 0.41)
			(layers "F.Cu" "F.Mask" "F.Paste")
			(net 179 "DDR3_DQ14")
			(pinfunction "DQ14")
			(pintype "bidirectional")
			(solder_mask_margin 0.03)
		)
		(pad "B9" smd circle
			(at 3.2 -5.2 180)
			(size 0.41 0.41)
			(layers "F.Cu" "F.Mask" "F.Paste")
			(net 1 "GND")
			(pinfunction "VSSQ")
			(pintype "passive")
			(solder_mask_margin 0.03)
		)
		(pad "C1" smd circle
			(at -3.2 -4.4 180)
			(size 0.41 0.41)
			(layers "F.Cu" "F.Mask" "F.Paste")
			(net 3 "VCC1V35")
			(pinfunction "VDDQ")
			(pintype "passive")
			(solder_mask_margin 0.03)
		)
		(pad "C2" smd circle
			(at -2.4 -4.4 180)
			(size 0.41 0.41)
			(layers "F.Cu" "F.Mask" "F.Paste")
			(net 184 "DDR3_DQ11")
			(pinfunction "DQ11")
			(pintype "bidirectional")
			(solder_mask_margin 0.03)
		)
		(pad "C3" smd circle
			(at -1.6 -4.4 180)
			(size 0.41 0.41)
			(layers "F.Cu" "F.Mask" "F.Paste")
			(net 180 "DDR3_DQ9")
			(pinfunction "DQ9")
			(pintype "bidirectional")
			(solder_mask_margin 0.03)
		)
		(pad "C7" smd circle
			(at 1.6 -4.4 180)
			(size 0.41 0.41)
			(layers "F.Cu" "F.Mask" "F.Paste")
			(net 475 "DDR3_DQS1_P")
			(pinfunction "UDQS")
			(pintype "bidirectional")
			(solder_mask_margin 0.03)
		)
		(pad "C8" smd circle
			(at 2.4 -4.4 180)
			(size 0.41 0.41)
			(layers "F.Cu" "F.Mask" "F.Paste")
			(net 183 "DDR3_DQ10")
			(pinfunction "DQ10")
			(pintype "bidirectional")
			(solder_mask_margin 0.03)
		)
		(pad "C9" smd circle
			(at 3.2 -4.4 180)
			(size 0.41 0.41)
			(layers "F.Cu" "F.Mask" "F.Paste")
			(net 3 "VCC1V35")
			(pinfunction "VDDQ")
			(pintype "passive")
			(solder_mask_margin 0.03)
		)
		(pad "D1" smd circle
			(at -3.2 -3.6 180)
			(size 0.41 0.41)
			(layers "F.Cu" "F.Mask" "F.Paste")
			(net 1 "GND")
			(pinfunction "VSSQ")
			(pintype "passive")
			(solder_mask_margin 0.03)
		)
		(pad "D2" smd circle
			(at -2.4 -3.6 180)
			(size 0.41 0.41)
			(layers "F.Cu" "F.Mask" "F.Paste")
			(net 3 "VCC1V35")
			(pinfunction "VDDQ")
			(pintype "passive")
			(solder_mask_margin 0.03)
		)
		(pad "D3" smd circle
			(at -1.6 -3.6 180)
			(size 0.41 0.41)
			(layers "F.Cu" "F.Mask" "F.Paste")
			(net 181 "DDR3_DM1")
			(pinfunction "UDM")
			(pintype "input")
			(solder_mask_margin 0.03)
		)
		(pad "D7" smd circle
			(at 1.6 -3.6 180)
			(size 0.41 0.41)
			(layers "F.Cu" "F.Mask" "F.Paste")
			(net 193 "DDR3_DQ8")
			(pinfunction "DQ8")
			(pintype "bidirectional")
			(solder_mask_margin 0.03)
		)
		(pad "D8" smd circle
			(at 2.4 -3.6 180)
			(size 0.41 0.41)
			(layers "F.Cu" "F.Mask" "F.Paste")
			(net 1 "GND")
			(pinfunction "VSSQ")
			(pintype "passive")
			(solder_mask_margin 0.03)
		)
		(pad "D9" smd circle
			(at 3.2 -3.6 180)
			(size 0.41 0.41)
			(layers "F.Cu" "F.Mask" "F.Paste")
			(net 3 "VCC1V35")
			(pinfunction "VDD")
			(pintype "passive")
			(solder_mask_margin 0.03)
		)
		(pad "E1" smd circle
			(at -3.2 -2.8 180)
			(size 0.41 0.41)
			(layers "F.Cu" "F.Mask" "F.Paste")
			(net 1 "GND")
			(pinfunction "VSS")
			(pintype "passive")
			(solder_mask_margin 0.03)
		)
		(pad "E2" smd circle
			(at -2.4 -2.8 180)
			(size 0.41 0.41)
			(layers "F.Cu" "F.Mask" "F.Paste")
			(net 1 "GND")
			(pinfunction "VSSQ")
			(pintype "passive")
			(solder_mask_margin 0.03)
		)
		(pad "E3" smd circle
			(at -1.6 -2.8 180)
			(size 0.41 0.41)
			(layers "F.Cu" "F.Mask" "F.Paste")
			(net 194 "DDR3_DQ0")
			(pinfunction "DQ0")
			(pintype "bidirectional")
			(solder_mask_margin 0.03)
		)
		(pad "E7" smd circle
			(at 1.6 -2.8 180)
			(size 0.41 0.41)
			(layers "F.Cu" "F.Mask" "F.Paste")
			(net 176 "DDR3_DM0")
			(pinfunction "LDM")
			(pintype "input")
			(solder_mask_margin 0.03)
		)
		(pad "E8" smd circle
			(at 2.4 -2.8 180)
			(size 0.41 0.41)
			(layers "F.Cu" "F.Mask" "F.Paste")
			(net 1 "GND")
			(pinfunction "VSSQ")
			(pintype "passive")
			(solder_mask_margin 0.03)
		)
		(pad "E9" smd circle
			(at 3.2 -2.8 180)
			(size 0.41 0.41)
			(layers "F.Cu" "F.Mask" "F.Paste")
			(net 3 "VCC1V35")
			(pinfunction "VDDQ")
			(pintype "passive")
			(solder_mask_margin 0.03)
		)
		(pad "F1" smd circle
			(at -3.2 -2 180)
			(size 0.41 0.41)
			(layers "F.Cu" "F.Mask" "F.Paste")
			(net 3 "VCC1V35")
			(pinfunction "VDDQ")
			(pintype "passive")
			(solder_mask_margin 0.03)
		)
		(pad "F2" smd circle
			(at -2.4 -2 180)
			(size 0.41 0.41)
			(layers "F.Cu" "F.Mask" "F.Paste")
			(net 187 "DDR3_DQ2")
			(pinfunction "DQ2")
			(pintype "bidirectional")
			(solder_mask_margin 0.03)
		)
		(pad "F3" smd circle
			(at -1.6 -2 180)
			(size 0.41 0.41)
			(layers "F.Cu" "F.Mask" "F.Paste")
			(net 477 "DDR3_DQS0_P")
			(pinfunction "LDQS")
			(pintype "bidirectional")
			(solder_mask_margin 0.03)
		)
		(pad "F7" smd circle
			(at 1.6 -2 180)
			(size 0.41 0.41)
			(layers "F.Cu" "F.Mask" "F.Paste")
			(net 188 "DDR3_DQ1")
			(pinfunction "DQ1")
			(pintype "bidirectional")
			(solder_mask_margin 0.03)
		)
		(pad "F8" smd circle
			(at 2.4 -2 180)
			(size 0.41 0.41)
			(layers "F.Cu" "F.Mask" "F.Paste")
			(net 190 "DDR3_DQ3")
			(pinfunction "DQ3")
			(pintype "bidirectional")
			(solder_mask_margin 0.03)
		)
		(pad "F9" smd circle
			(at 3.2 -2 180)
			(size 0.41 0.41)
			(layers "F.Cu" "F.Mask" "F.Paste")
			(net 1 "GND")
			(pinfunction "VSSQ")
			(pintype "passive")
			(solder_mask_margin 0.03)
		)
		(pad "G1" smd circle
			(at -3.2 -1.2 180)
			(size 0.41 0.41)
			(layers "F.Cu" "F.Mask" "F.Paste")
			(net 1 "GND")
			(pinfunction "VSSQ")
			(pintype "passive")
			(solder_mask_margin 0.03)
		)
		(pad "G2" smd circle
			(at -2.4 -1.2 180)
			(size 0.41 0.41)
			(layers "F.Cu" "F.Mask" "F.Paste")
			(net 192 "DDR3_DQ6")
			(pinfunction "DQ6")
			(pintype "bidirectional")
			(solder_mask_margin 0.03)
		)
		(pad "G3" smd circle
			(at -1.6 -1.2 180)
			(size 0.41 0.41)
			(layers "F.Cu" "F.Mask" "F.Paste")
			(net 476 "DDR3_DQS0_N")
			(pinfunction "~{LDQS}")
			(pintype "bidirectional")
			(solder_mask_margin 0.03)
		)
		(pad "G7" smd circle
			(at 1.6 -1.2 180)
			(size 0.41 0.41)
			(layers "F.Cu" "F.Mask" "F.Paste")
			(net 3 "VCC1V35")
			(pinfunction "VDD")
			(pintype "passive")
			(solder_mask_margin 0.03)
		)
		(pad "G8" smd circle
			(at 2.4 -1.2 180)
			(size 0.41 0.41)
			(layers "F.Cu" "F.Mask" "F.Paste")
			(net 1 "GND")
			(pinfunction "VSS")
			(pintype "passive")
			(solder_mask_margin 0.03)
		)
		(pad "G9" smd circle
			(at 3.2 -1.2 180)
			(size 0.41 0.41)
			(layers "F.Cu" "F.Mask" "F.Paste")
			(net 1 "GND")
			(pinfunction "VSSQ")
			(pintype "passive")
			(solder_mask_margin 0.03)
		)
		(pad "H1" smd circle
			(at -3.2 -0.4 180)
			(size 0.41 0.41)
			(layers "F.Cu" "F.Mask" "F.Paste")
			(net 211 "DDR3_VREF")
			(pinfunction "VREF_DQ")
			(pintype "power_in")
			(solder_mask_margin 0.03)
		)
		(pad "H2" smd circle
			(at -2.4 -0.4 180)
			(size 0.41 0.41)
			(layers "F.Cu" "F.Mask" "F.Paste")
			(net 3 "VCC1V35")
			(pinfunction "VDDQ")
			(pintype "passive")
			(solder_mask_margin 0.03)
		)
		(pad "H3" smd circle
			(at -1.6 -0.4 180)
			(size 0.41 0.41)
			(layers "F.Cu" "F.Mask" "F.Paste")
			(net 189 "DDR3_DQ4")
			(pinfunction "DQ4")
			(pintype "bidirectional")
			(solder_mask_margin 0.03)
		)
		(pad "H7" smd circle
			(at 1.6 -0.4 180)
			(size 0.41 0.41)
			(layers "F.Cu" "F.Mask" "F.Paste")
			(net 185 "DDR3_DQ7")
			(pinfunction "DQ7")
			(pintype "bidirectional")
			(solder_mask_margin 0.03)
		)
		(pad "H8" smd circle
			(at 2.4 -0.4 180)
			(size 0.41 0.41)
			(layers "F.Cu" "F.Mask" "F.Paste")
			(net 186 "DDR3_DQ5")
			(pinfunction "DQ5")
			(pintype "bidirectional")
			(solder_mask_margin 0.03)
		)
		(pad "H9" smd circle
			(at 3.2 -0.4 180)
			(size 0.41 0.41)
			(layers "F.Cu" "F.Mask" "F.Paste")
			(net 3 "VCC1V35")
			(pinfunction "VDDQ")
			(pintype "passive")
			(solder_mask_margin 0.03)
		)
		(pad "J1" smd circle
			(at -3.2 0.4 180)
			(size 0.41 0.41)
			(layers "F.Cu" "F.Mask" "F.Paste")
			(net 698 "unconnected-(U7-NC-PadJ1)")
			(pinfunction "NC")
			(pintype "no_connect")
			(solder_mask_margin 0.03)
		)
		(pad "J2" smd circle
			(at -2.4 0.4 180)
			(size 0.41 0.41)
			(layers "F.Cu" "F.Mask" "F.Paste")
			(net 1 "GND")
			(pinfunction "VSS")
			(pintype "passive")
			(solder_mask_margin 0.03)
		)
		(pad "J3" smd circle
			(at -1.6 0.4 180)
			(size 0.41 0.41)
			(layers "F.Cu" "F.Mask" "F.Paste")
			(net 162 "DDR3_RAS")
			(pinfunction "~{RAS}")
			(pintype "input")
			(solder_mask_margin 0.03)
		)
		(pad "J7" smd circle
			(at 1.6 0.4 180)
			(size 0.41 0.41)
			(layers "F.Cu" "F.Mask" "F.Paste")
			(net 479 "DDR3_CLK_P")
			(pinfunction "CK")
			(pintype "input")
			(solder_mask_margin 0.03)
		)
		(pad "J8" smd circle
			(at 2.4 0.4 180)
			(size 0.41 0.41)
			(layers "F.Cu" "F.Mask" "F.Paste")
			(net 1 "GND")
			(pinfunction "VSS")
			(pintype "passive")
			(solder_mask_margin 0.03)
		)
		(pad "J9" smd circle
			(at 3.2 0.4 180)
			(size 0.41 0.41)
			(layers "F.Cu" "F.Mask" "F.Paste")
			(net 700 "unconnected-(U7-NC-PadJ9)")
			(pinfunction "NC")
			(pintype "no_connect")
			(solder_mask_margin 0.03)
		)
		(pad "K1" smd circle
			(at -3.2 1.2 180)
			(size 0.41 0.41)
			(layers "F.Cu" "F.Mask" "F.Paste")
			(net 161 "DDR3_ODT")
			(pinfunction "ODT")
			(pintype "input")
			(solder_mask_margin 0.03)
		)
		(pad "K2" smd circle
			(at -2.4 1.2 180)
			(size 0.41 0.41)
			(layers "F.Cu" "F.Mask" "F.Paste")
			(net 3 "VCC1V35")
			(pinfunction "VDD")
			(pintype "passive")
			(solder_mask_margin 0.03)
		)
		(pad "K3" smd circle
			(at -1.6 1.2 180)
			(size 0.41 0.41)
			(layers "F.Cu" "F.Mask" "F.Paste")
			(net 166 "DDR3_CAS")
			(pinfunction "~{CAS}")
			(pintype "input")
			(solder_mask_margin 0.03)
		)
		(pad "K7" smd circle
			(at 1.6 1.2 180)
			(size 0.41 0.41)
			(layers "F.Cu" "F.Mask" "F.Paste")
			(net 478 "DDR3_CLK_N")
			(pinfunction "~{CK}")
			(pintype "input")
			(solder_mask_margin 0.03)
		)
		(pad "K8" smd circle
			(at 2.4 1.2 180)
			(size 0.41 0.41)
			(layers "F.Cu" "F.Mask" "F.Paste")
			(net 3 "VCC1V35")
			(pinfunction "VDD")
			(pintype "passive")
			(solder_mask_margin 0.03)
		)
		(pad "K9" smd circle
			(at 3.2 1.2 180)
			(size 0.41 0.41)
			(layers "F.Cu" "F.Mask" "F.Paste")
			(net 160 "DDR3_CKE")
			(pinfunction "CKE")
			(pintype "input")
			(solder_mask_margin 0.03)
		)
		(pad "L1" smd circle
			(at -3.2 2 180)
			(size 0.41 0.41)
			(layers "F.Cu" "F.Mask" "F.Paste")
			(net 699 "unconnected-(U7-NC-PadL1)")
			(pinfunction "NC")
			(pintype "no_connect")
			(solder_mask_margin 0.03)
		)
		(pad "L2" smd circle
			(at -2.4 2 180)
			(size 0.41 0.41)
			(layers "F.Cu" "F.Mask" "F.Paste")
			(net 163 "DDR3_CS")
			(pinfunction "~{CS}")
			(pintype "input")
			(solder_mask_margin 0.03)
		)
		(pad "L3" smd circle
			(at -1.6 2 180)
			(size 0.41 0.41)
			(layers "F.Cu" "F.Mask" "F.Paste")
			(net 153 "DDR3_WE")
			(pinfunction "~{WE}")
			(pintype "input")
			(solder_mask_margin 0.03)
		)
		(pad "L7" smd circle
			(at 1.6 2 180)
			(size 0.41 0.41)
			(layers "F.Cu" "F.Mask" "F.Paste")
			(net 154 "DDR3_A10")
			(pinfunction "A10/AP")
			(pintype "input")
			(solder_mask_margin 0.03)
		)
		(pad "L8" smd circle
			(at 2.4 2 180)
			(size 0.41 0.41)
			(layers "F.Cu" "F.Mask" "F.Paste")
			(net 337 "Net-(U7-ZQ)")
			(pinfunction "ZQ")
			(pintype "passive")
			(solder_mask_margin 0.03)
		)
		(pad "L9" smd circle
			(at 3.2 2 180)
			(size 0.41 0.41)
			(layers "F.Cu" "F.Mask" "F.Paste")
			(net 701 "unconnected-(U7-NC-PadL9)")
			(pinfunction "NC")
			(pintype "no_connect")
			(solder_mask_margin 0.03)
		)
		(pad "M1" smd circle
			(at -3.2 2.8 180)
			(size 0.41 0.41)
			(layers "F.Cu" "F.Mask" "F.Paste")
			(net 1 "GND")
			(pinfunction "VSS")
			(pintype "passive")
			(solder_mask_margin 0.03)
		)
		(pad "M2" smd circle
			(at -2.4 2.8 180)
			(size 0.41 0.41)
			(layers "F.Cu" "F.Mask" "F.Paste")
			(net 164 "DDR3_BA0")
			(pinfunction "BA0")
			(pintype "input")
			(solder_mask_margin 0.03)
		)
		(pad "M3" smd circle
			(at -1.6 2.8 180)
			(size 0.41 0.41)
			(layers "F.Cu" "F.Mask" "F.Paste")
			(net 152 "DDR3_BA2")
			(pinfunction "BA2")
			(pintype "input")
			(solder_mask_margin 0.03)
		)
		(pad "M7" smd circle
			(at 1.6 2.8 180)
			(size 0.41 0.41)
			(layers "F.Cu" "F.Mask" "F.Paste")
			(net 697 "unconnected-(U7-NC-PadM7)")
			(pinfunction "NC")
			(pintype "no_connect")
			(solder_mask_margin 0.03)
		)
		(pad "M8" smd circle
			(at 2.4 2.8 180)
			(size 0.41 0.41)
			(layers "F.Cu" "F.Mask" "F.Paste")
			(net 211 "DDR3_VREF")
			(pinfunction "VREF_CA")
			(pintype "power_in")
			(solder_mask_margin 0.03)
		)
		(pad "M9" smd circle
			(at 3.2 2.8 180)
			(size 0.41 0.41)
			(layers "F.Cu" "F.Mask" "F.Paste")
			(net 1 "GND")
			(pinfunction "VSS")
			(pintype "passive")
			(solder_mask_margin 0.03)
		)
		(pad "N1" smd circle
			(at -3.2 3.6 180)
			(size 0.41 0.41)
			(layers "F.Cu" "F.Mask" "F.Paste")
			(net 3 "VCC1V35")
			(pinfunction "VDD")
			(pintype "passive")
			(solder_mask_margin 0.03)
		)
		(pad "N2" smd circle
			(at -2.4 3.6 180)
			(size 0.41 0.41)
			(layers "F.Cu" "F.Mask" "F.Paste")
			(net 165 "DDR3_A3")
			(pinfunction "A3")
			(pintype "input")
			(solder_mask_margin 0.03)
		)
		(pad "N3" smd circle
			(at -1.6 3.6 180)
			(size 0.41 0.41)
			(layers "F.Cu" "F.Mask" "F.Paste")
			(net 158 "DDR3_A0")
			(pinfunction "A0")
			(pintype "input")
			(solder_mask_margin 0.03)
		)
		(pad "N7" smd circle
			(at 1.6 3.6 180)
			(size 0.41 0.41)
			(layers "F.Cu" "F.Mask" "F.Paste")
			(net 156 "DDR3_A12")
			(pinfunction "A12/~{BC}")
			(pintype "input")
			(solder_mask_margin 0.03)
		)
	)
)
